# S9S_MB_2U (Grand Teton) — schematic netlist excerpt (pin names and nets, part order shuffled) for the footprints in the layout excerpt that follows; sources: Cadence DE-HDL packaged netlist, KiCad conversion of 03242023_DA0F0TMBIJ0_F0T_Motherboard_J_brd_V01_OCP.brd

R4532  Q_RES  10K 1% CHIP  pkg 0402LF  page 157 : A = P3V3_AUX ; B = HP_LVC3_OCP_V3_1_P12V_PWRGD
R4147  Q_RES  33.2 1% CHIP  pkg 0402LF  page 215 : A = PRSNT_CABLE_GPU_A2_ISO_N ; B = PRSNT_CABLE_GPU_A2_ISO_R_N

(kicad_pcb
	(version 20260206)
	(generator "pcbnew")
	(generator_version "10.0")
	(general
		(thickness 1.6)
		(legacy_teardrops no)
	)
	(paper "A4")
	(title_block
		(title "03242023_DA0F0TMBIJ0_F0T_Motherboard_J_brd_V01_OCP.brd")
		(comment 1 "Grand Teton / footprints 2107-2108 of 6105")
	)
	(layers
		(0 "F.Cu" signal "TOP")
		(4 "In1.Cu" signal "GND")
		(6 "In2.Cu" signal "IN1")
		(8 "In3.Cu" signal "GND1")
		(10 "In4.Cu" signal "IN2")
		(12 "In5.Cu" signal "GND2")
		(14 "In6.Cu" signal "IN3")
		(16 "In7.Cu" signal "GND3")
		(18 "In8.Cu" signal "VCC")
		(20 "In9.Cu" signal "VCC1")
		(22 "In10.Cu" signal "GND4")
		(24 "In11.Cu" signal "IN4")
		(26 "In12.Cu" signal "GND5")
		(28 "In13.Cu" signal "IN5")
		(30 "In14.Cu" signal "GND6")
		(32 "In15.Cu" signal "IN6")
		(34 "In16.Cu" signal "GND7")
		(2 "B.Cu" signal "BOTTOM")
		(9 "F.Adhes" user "F.Adhesive")
		(11 "B.Adhes" user "B.Adhesive")
		(13 "F.Paste" user "Package Geometry/Pastemask Top")
		(15 "B.Paste" user "Package Geometry/Pastemask Bottom")
		(5 "F.SilkS" user "Ref Des/Silkscreen Top")
		(7 "B.SilkS" user "Ref Des/Silkscreen Bottom")
		(1 "F.Mask" user "Board Geometry/Soldermask Top")
		(3 "B.Mask" user "Board Geometry/Soldermask Bottom")
		(17 "Dwgs.User" user "User.Drawings")
		(19 "Cmts.User" user "User.Comments")
		(21 "Eco1.User" user "User.Eco1")
		(23 "Eco2.User" user "User.Eco2")
		(25 "Edge.Cuts" user "Board Geometry/Outline")
		(27 "Margin" user)
		(31 "F.CrtYd" user "Package Geometry/Place Bound Top")
		(29 "B.CrtYd" user "Package Geometry/Place Bound Bottom")
		(35 "F.Fab" user "Ref Des/Assembly Top")
		(33 "B.Fab" user "Ref Des/Assembly Bottom")
	)
	(footprint ""
		(layer "F.Cu")
		(at 204.93736 -114.264948 180)
		(property "Reference" "R4147"
			(at 0 0 180)
			(layer "F.SilkS")
			(hide yes)
			(effects
				(font
					(size 1.27 1.27)
				)
			)
		)
		(property "Value" ""
			(at 0 0 180)
			(layer "F.Fab")
			(effects
				(font
					(size 1.27 1.27)
				)
			)
		)
		(duplicate_pad_numbers_are_jumpers no)
		(fp_line
			(start 0.7874 0.4064)
			(end -0.7874 0.4064)
			(stroke
				(width 0.1524)
				(type default)
			)
			(layer "F.SilkS")
		)
		(fp_line
			(start 0.7874 -0.4064)
			(end 0.7874 0.4064)
			(stroke
				(width 0.1524)
				(type default)
			)
			(layer "F.SilkS")
		)
		(fp_line
			(start -0.7874 0.4064)
			(end -0.7874 -0.4064)
			(stroke
				(width 0.1524)
				(type default)
			)
			(layer "F.SilkS")
		)
		(fp_line
			(start -0.7874 -0.4064)
			(end 0.7874 -0.4064)
			(stroke
				(width 0.1524)
				(type default)
			)
			(layer "F.SilkS")
		)
		(fp_line
			(start 0.67945 0.3048)
			(end 0.120396 0.3048)
			(stroke
				(width 0.1)
				(type default)
			)
			(layer "F.Fab")
		)
		(fp_line
			(start 0.67945 -0.3048)
			(end 0.67945 0.3048)
			(stroke
				(width 0.1)
				(type default)
			)
			(layer "F.Fab")
		)
		(fp_line
			(start 0.12065 -0.2794)
			(end 0.12065 -0.3048)
			(stroke
				(width 0.1)
				(type default)
			)
			(layer "F.Fab")
		)
		(fp_line
			(start 0.12065 -0.3048)
			(end 0.67945 -0.3048)
			(stroke
				(width 0.1)
				(type default)
			)
			(layer "F.Fab")
		)
		(fp_line
			(start 0.120396 0.3048)
			(end 0.120396 0.2794)
			(stroke
				(width 0.1)
				(type default)
			)
			(layer "F.Fab")
		)
		(fp_line
			(start 0.120396 0.2794)
			(end -0.12065 0.2794)
			(stroke
				(width 0.1)
				(type default)
			)
			(layer "F.Fab")
		)
		(fp_line
			(start -0.12065 0.3048)
			(end -0.67945 0.3048)
			(stroke
				(width 0.1)
				(type default)
			)
			(layer "F.Fab")
		)
		(fp_line
			(start -0.12065 0.2794)
			(end -0.12065 0.3048)
			(stroke
				(width 0.1)
				(type default)
			)
			(layer "F.Fab")
		)
		(fp_line
			(start -0.12065 -0.2794)
			(end 0.12065 -0.2794)
			(stroke
				(width 0.1)
				(type default)
			)
			(layer "F.Fab")
		)
		(fp_line
			(start -0.12065 -0.305054)
			(end -0.12065 -0.2794)
			(stroke
				(width 0.1)
				(type default)
			)
			(layer "F.Fab")
		)
		(fp_line
			(start -0.67945 0.3048)
			(end -0.67945 -0.305054)
			(stroke
				(width 0.1)
				(type default)
			)
			(layer "F.Fab")
		)
		(fp_line
			(start -0.67945 -0.305054)
			(end -0.12065 -0.305054)
			(stroke
				(width 0.1)
				(type default)
			)
			(layer "F.Fab")
		)
		(pad "1" smd circle
			(at -0.40005 0 180)
			(size 0 0)
			(layers "F.Cu" "F.Mask" "F.Paste")
			(net "PRSNT_CABLE_GPU_A2_ISO_N")
		)
		(pad "2" smd circle
			(at 0.40005 0 180)
			(size 0 0)
			(layers "F.Cu" "F.Mask" "F.Paste")
			(net "PRSNT_CABLE_GPU_A2_ISO_R_N")
		)
	)
	(footprint ""
		(layer "F.Cu")
		(at 437.875172 -28.668218)
		(property "Reference" "R4532"
			(at 0 0 0)
			(layer "F.SilkS")
			(hide yes)
			(effects
				(font
					(size 1.27 1.27)
				)
			)
		)
		(property "Value" ""
			(at 0 0 0)
			(layer "F.Fab")
			(effects
				(font
					(size 1.27 1.27)
				)
			)
		)
		(duplicate_pad_numbers_are_jumpers no)
		(fp_line
			(start -0.7874 -0.4064)
			(end 0.7874 -0.4064)
			(stroke
				(width 0.1524)
				(type default)
			)
			(layer "F.SilkS")
		)
		(fp_line
			(start -0.7874 0.4064)
			(end -0.7874 -0.4064)
			(stroke
				(width 0.1524)
				(type default)
			)
			(layer "F.SilkS")
		)
		(fp_line
			(start 0.7874 -0.4064)
			(end 0.7874 0.4064)
			(stroke
				(width 0.1524)
				(type default)
			)
			(layer "F.SilkS")
		)
		(fp_line
			(start 0.7874 0.4064)
			(end -0.7874 0.4064)
			(stroke
				(width 0.1524)
				(type default)
			)
			(layer "F.SilkS")
		)
		(fp_line
			(start -0.67945 -0.305054)
			(end -0.12065 -0.305054)
			(stroke
				(width 0.1)
				(type default)
			)
			(layer "F.Fab")
		)
		(fp_line
			(start -0.67945 0.3048)
			(end -0.67945 -0.305054)
			(stroke
				(width 0.1)
				(type default)
			)
			(layer "F.Fab")
		)
		(fp_line
			(start -0.12065 -0.305054)
			(end -0.12065 -0.2794)
			(stroke
				(width 0.1)
				(type default)
			)
			(layer "F.Fab")
		)
		(fp_line
			(start -0.12065 -0.2794)
			(end 0.12065 -0.2794)
			(stroke
				(width 0.1)
				(type default)
			)
			(layer "F.Fab")
		)
		(fp_line
			(start -0.12065 0.2794)
			(end -0.12065 0.3048)
			(stroke
				(width 0.1)
				(type default)
			)
			(layer "F.Fab")
		)
		(fp_line
			(start -0.12065 0.3048)
			(end -0.67945 0.3048)
			(stroke
				(width 0.1)
				(type default)
			)
			(layer "F.Fab")
		)
		(fp_line
			(start 0.120396 0.2794)
			(end -0.12065 0.2794)
			(stroke
				(width 0.1)
				(type default)
			)
			(layer "F.Fab")
		)
		(fp_line
			(start 0.120396 0.3048)
			(end 0.120396 0.2794)
			(stroke
				(width 0.1)
				(type default)
			)
			(layer "F.Fab")
		)
		(fp_line
			(start 0.12065 -0.3048)
			(end 0.67945 -0.3048)
			(stroke
				(width 0.1)
				(type default)
			)
			(layer "F.Fab")
		)
		(fp_line
			(start 0.12065 -0.2794)
			(end 0.12065 -0.3048)
			(stroke
				(width 0.1)
				(type default)
			)
			(layer "F.Fab")
		)
		(fp_line
			(start 0.67945 -0.3048)
			(end 0.67945 0.3048)
			(stroke
				(width 0.1)
				(type default)
			)
			(layer "F.Fab")
		)
		(fp_line
			(start 0.67945 0.3048)
			(end 0.120396 0.3048)
			(stroke
				(width 0.1)
				(type default)
			)
			(layer "F.Fab")
		)
		(pad "1" smd circle
			(at -0.40005 0)
			(size 0 0)
			(layers "F.Cu" "F.Mask" "F.Paste")
			(net "P3V3_AUX")
		)
		(pad "2" smd circle
			(at 0.40005 0)
			(size 0 0)
			(layers "F.Cu" "F.Mask" "F.Paste")
			(net "HP_LVC3_OCP_V3_1_P12V_PWRGD")
		)
	)
)
